(kicad_pcb
	(version 20260206)
	(generator "pcbnew")
	(generator_version "10.0")
	(general
		(thickness 1.6)
		(legacy_teardrops no)
	)
	(paper "A4")
	(title_block
		(title "Wiwynn_Tioga_Pass_MB.brd")
		(comment 1 "Tioga Pass / footprints 1820-1827 of 4770")
	)
	(layers
		(0 "F.Cu" signal "TOP")
		(4 "In1.Cu" signal "L2GND")
		(6 "In2.Cu" signal "L3")
		(8 "In3.Cu" signal "L4GND")
		(10 "In4.Cu" signal "L5")
		(12 "In5.Cu" signal "L6GND")
		(14 "In6.Cu" signal "L7VCC")
		(16 "In7.Cu" signal "L8VCC")
		(18 "In8.Cu" signal "L9GND")
		(20 "In9.Cu" signal "L10")
		(22 "In10.Cu" signal "L11GND")
		(24 "In11.Cu" signal "L12")
		(26 "In12.Cu" signal "L13GND")
		(2 "B.Cu" signal "BOTTOM")
		(9 "F.Adhes" user "F.Adhesive")
		(11 "B.Adhes" user "B.Adhesive")
		(13 "F.Paste" user "Package Geometry/Pastemask Top")
		(15 "B.Paste" user "Package Geometry/Pastemask Bottom")
		(5 "F.SilkS" user "Ref Des/Silkscreen Top")
		(7 "B.SilkS" user "Ref Des/Silkscreen Bottom")
		(1 "F.Mask" user "Board Geometry/Soldermask Top")
		(3 "B.Mask" user "Board Geometry/Soldermask Bottom")
		(17 "Dwgs.User" user "User.Drawings")
		(19 "Cmts.User" user "User.Comments")
		(21 "Eco1.User" user "User.Eco1")
		(23 "Eco2.User" user "User.Eco2")
		(25 "Edge.Cuts" user "Board Geometry/Outline")
		(27 "Margin" user)
		(31 "F.CrtYd" user "Package Geometry/Place Bound Top")
		(29 "B.CrtYd" user "Package Geometry/Place Bound Bottom")
		(35 "F.Fab" user "Ref Des/Assembly Top")
		(33 "B.Fab" user "Ref Des/Assembly Bottom")
	)
	(footprint ""
		(layer "F.Cu")
		(at 426.681646 -48.968152)
		(property "Reference" "R25W83"
			(at -0.8382 -0.67818 0)
			(unlocked yes)
			(layer "F.SilkS")
			(effects
				(font
					(size 0.4064 0.254)
					(thickness 0.1524)
				)
				(justify left)
			)
		)
		(property "Value" ""
			(at 0 0 0)
			(layer "F.Fab")
			(effects
				(font
					(size 1.27 1.27)
				)
			)
		)
		(duplicate_pad_numbers_are_jumpers no)
		(fp_poly
			(pts
				(xy -0.2794 -0.1016) (xy 0.2794 -0.1016) (xy 0.2794 0.9906) (xy -0.2794 0.9906)
			)
			(stroke
				(width 0)
				(type default)
			)
			(fill no)
			(layer "F.CrtYd")
		)
		(fp_line
			(start -0.2794 -0.1016)
			(end -0.2794 0.9906)
			(stroke
				(width 0.1)
				(type default)
			)
			(layer "F.Fab")
		)
		(fp_line
			(start -0.2794 0.9906)
			(end 0.2794 0.9906)
			(stroke
				(width 0.1)
				(type default)
			)
			(layer "F.Fab")
		)
		(fp_line
			(start 0.2794 -0.1016)
			(end -0.2794 -0.1016)
			(stroke
				(width 0.1)
				(type default)
			)
			(layer "F.Fab")
		)
		(fp_line
			(start 0.2794 0.9906)
			(end 0.2794 -0.1016)
			(stroke
				(width 0.1)
				(type default)
			)
			(layer "F.Fab")
		)
		(pad "1" smd rect
			(at 0 0)
			(size 0.508 0.508)
			(layers "F.Cu" "F.Mask" "F.Paste")
			(net "FM_BMC_NMI_N")
		)
		(pad "2" smd rect
			(at 0 0.889)
			(size 0.508 0.508)
			(layers "F.Cu" "F.Mask" "F.Paste")
			(net "FM_BMC_NMI_N_R")
		)
		(zone
			(layer "F.Cu")
			(hatch none 0.5)
			(connect_pads
				(clearance 0)
			)
			(min_thickness 0.25)
			(keepout
				(tracks allowed)
				(vias not_allowed)
				(pads allowed)
				(copperpour not_allowed)
				(footprints allowed)
			)
			(placement
				(enabled no)
				(sheetname "")
			)
			(fill
				(thermal_gap 0.5)
				(thermal_bridge_width 0.5)
				(island_removal_mode 0)
			)
			(polygon
				(pts
					(xy 426.427646 -48.714152) (xy 426.935646 -48.714152) (xy 426.935646 -48.333152) (xy 426.427646 -48.333152)
				)
			)
		)
		(zone
			(layer "F.Cu")
			(hatch none 0.5)
			(connect_pads
				(clearance 0)
			)
			(min_thickness 0.25)
			(keepout
				(tracks not_allowed)
				(vias allowed)
				(pads allowed)
				(copperpour not_allowed)
				(footprints allowed)
			)
			(placement
				(enabled no)
				(sheetname "")
			)
			(fill
				(thermal_gap 0.5)
				(thermal_bridge_width 0.5)
				(island_removal_mode 0)
			)
			(polygon
				(pts
					(xy 426.427646 -48.333152) (xy 426.935646 -48.333152) (xy 426.935646 -48.714152) (xy 426.427646 -48.714152)
				)
			)
		)
	)
	(footprint ""
		(layer "F.Cu")
		(at 113.427002 -77.382116)
		(property "Reference" "C3D15"
			(at 0 0 0)
			(layer "F.SilkS")
			(hide yes)
			(effects
				(font
					(size 1.27 1.27)
				)
			)
		)
		(property "Value" ""
			(at 0 0 0)
			(layer "F.Fab")
			(effects
				(font
					(size 1.27 1.27)
				)
			)
		)
		(duplicate_pad_numbers_are_jumpers no)
		(fp_poly
			(pts
				(xy -0.4953 -0.2032) (xy 0.4953 -0.2032) (xy 0.4953 1.6002) (xy -0.4953 1.6002)
			)
			(stroke
				(width 0)
				(type default)
			)
			(fill no)
			(layer "F.CrtYd")
		)
		(fp_line
			(start -0.4953 -0.2032)
			(end 0.4953 -0.2032)
			(stroke
				(width 0.1)
				(type default)
			)
			(layer "F.Fab")
		)
		(fp_line
			(start -0.4953 1.6002)
			(end -0.4953 -0.2032)
			(stroke
				(width 0.1)
				(type default)
			)
			(layer "F.Fab")
		)
		(fp_line
			(start 0.4953 -0.2032)
			(end 0.4953 1.6002)
			(stroke
				(width 0.1)
				(type default)
			)
			(layer "F.Fab")
		)
		(fp_line
			(start 0.4953 1.6002)
			(end -0.4953 1.6002)
			(stroke
				(width 0.1)
				(type default)
			)
			(layer "F.Fab")
		)
		(pad "1" smd rect
			(at 0 0)
			(size 0.762 0.889)
			(layers "F.Cu" "F.Mask" "F.Paste")
			(net "PVCCIO_CPU1")
		)
		(pad "2" smd rect
			(at 0 1.397)
			(size 0.762 0.889)
			(layers "F.Cu" "F.Mask" "F.Paste")
			(net "GND")
		)
		(zone
			(layer "F.Cu")
			(hatch none 0.5)
			(connect_pads
				(clearance 0)
			)
			(min_thickness 0.25)
			(keepout
				(tracks not_allowed)
				(vias allowed)
				(pads allowed)
				(copperpour not_allowed)
				(footprints allowed)
			)
			(placement
				(enabled no)
				(sheetname "")
			)
			(fill
				(thermal_gap 0.5)
				(thermal_bridge_width 0.5)
				(island_removal_mode 0)
			)
			(polygon
				(pts
					(xy 113.046002 -76.937616) (xy 113.808002 -76.937616) (xy 113.808002 -76.429616) (xy 113.046002 -76.429616)
				)
			)
		)
	)
	(footprint ""
		(layer "F.Cu")
		(at 153.5303 -22.7457 -90)
		(property "Reference" "C3F3"
			(at 0 0 270)
			(layer "F.SilkS")
			(hide yes)
			(effects
				(font
					(size 1.27 1.27)
				)
			)
		)
		(property "Value" ""
			(at 0 0 270)
			(layer "F.Fab")
			(effects
				(font
					(size 1.27 1.27)
				)
			)
		)
		(duplicate_pad_numbers_are_jumpers no)
		(fp_poly
			(pts
				(xy -0.4953 -0.2032) (xy 0.4953 -0.2032) (xy 0.4953 1.6002) (xy -0.4953 1.6002)
			)
			(stroke
				(width 0)
				(type default)
			)
			(fill no)
			(layer "F.CrtYd")
		)
		(fp_line
			(start -0.4953 1.6002)
			(end -0.4953 -0.2032)
			(stroke
				(width 0.1)
				(type default)
			)
			(layer "F.Fab")
		)
		(fp_line
			(start 0.4953 1.6002)
			(end -0.4953 1.6002)
			(stroke
				(width 0.1)
				(type default)
			)
			(layer "F.Fab")
		)
		(fp_line
			(start -0.4953 -0.2032)
			(end 0.4953 -0.2032)
			(stroke
				(width 0.1)
				(type default)
			)
			(layer "F.Fab")
		)
		(fp_line
			(start 0.4953 -0.2032)
			(end 0.4953 1.6002)
			(stroke
				(width 0.1)
				(type default)
			)
			(layer "F.Fab")
		)
		(pad "1" smd rect
			(at 0 0 270)
			(size 0.762 0.889)
			(layers "F.Cu" "F.Mask" "F.Paste")
			(net "PVPP_GHJ")
		)
		(pad "2" smd rect
			(at 0 1.397 270)
			(size 0.762 0.889)
			(layers "F.Cu" "F.Mask" "F.Paste")
			(net "GND")
		)
		(zone
			(layer "F.Cu")
			(hatch none 0.5)
			(connect_pads
				(clearance 0)
			)
			(min_thickness 0.25)
			(keepout
				(tracks not_allowed)
				(vias allowed)
				(pads allowed)
				(copperpour not_allowed)
				(footprints allowed)
			)
			(placement
				(enabled no)
				(sheetname "")
			)
			(fill
				(thermal_gap 0.5)
				(thermal_bridge_width 0.5)
				(island_removal_mode 0)
			)
			(polygon
				(pts
					(xy 153.0858 -23.1267) (xy 153.0858 -22.3647) (xy 152.5778 -22.3647) (xy 152.5778 -23.1267)
				)
			)
		)
	)
	(footprint ""
		(layer "F.Cu")
		(at 29.591 -2.877312 180)
		(property "Reference" "R1G17"
			(at 0 0 180)
			(layer "F.SilkS")
			(hide yes)
			(effects
				(font
					(size 1.27 1.27)
				)
			)
		)
		(property "Value" ""
			(at 0 0 180)
			(layer "F.Fab")
			(effects
				(font
					(size 1.27 1.27)
				)
			)
		)
		(duplicate_pad_numbers_are_jumpers no)
		(fp_poly
			(pts
				(xy -0.2794 -0.1016) (xy 0.2794 -0.1016) (xy 0.2794 0.9906) (xy -0.2794 0.9906)
			)
			(stroke
				(width 0)
				(type default)
			)
			(fill no)
			(layer "F.CrtYd")
		)
		(fp_line
			(start 0.2794 0.9906)
			(end 0.2794 -0.1016)
			(stroke
				(width 0.1)
				(type default)
			)
			(layer "F.Fab")
		)
		(fp_line
			(start 0.2794 -0.1016)
			(end -0.2794 -0.1016)
			(stroke
				(width 0.1)
				(type default)
			)
			(layer "F.Fab")
		)
		(fp_line
			(start -0.2794 0.9906)
			(end 0.2794 0.9906)
			(stroke
				(width 0.1)
				(type default)
			)
			(layer "F.Fab")
		)
		(fp_line
			(start -0.2794 -0.1016)
			(end -0.2794 0.9906)
			(stroke
				(width 0.1)
				(type default)
			)
			(layer "F.Fab")
		)
		(pad "1" smd rect
			(at 0 0 180)
			(size 0.508 0.508)
			(layers "F.Cu" "F.Mask" "F.Paste")
			(net "M_J_VREF")
		)
		(pad "2" smd rect
			(at 0 0.889 180)
			(size 0.508 0.508)
			(layers "F.Cu" "F.Mask" "F.Paste")
			(net "GND")
		)
		(zone
			(layer "F.Cu")
			(hatch none 0.5)
			(connect_pads
				(clearance 0)
			)
			(min_thickness 0.25)
			(keepout
				(tracks not_allowed)
				(vias allowed)
				(pads allowed)
				(copperpour not_allowed)
				(footprints allowed)
			)
			(placement
				(enabled no)
				(sheetname "")
			)
			(fill
				(thermal_gap 0.5)
				(thermal_bridge_width 0.5)
				(island_removal_mode 0)
			)
			(polygon
				(pts
					(xy 29.845 -3.512312) (xy 29.337 -3.512312) (xy 29.337 -3.131312) (xy 29.845 -3.131312)
				)
			)
		)
		(zone
			(layer "F.Cu")
			(hatch none 0.5)
			(connect_pads
				(clearance 0)
			)
			(min_thickness 0.25)
			(keepout
				(tracks allowed)
				(vias not_allowed)
				(pads allowed)
				(copperpour not_allowed)
				(footprints allowed)
			)
			(placement
				(enabled no)
				(sheetname "")
			)
			(fill
				(thermal_gap 0.5)
				(thermal_bridge_width 0.5)
				(island_removal_mode 0)
			)
			(polygon
				(pts
					(xy 29.845 -3.131312) (xy 29.337 -3.131312) (xy 29.337 -3.512312) (xy 29.845 -3.512312)
				)
			)
		)
	)
	(footprint ""
		(layer "F.Cu")
		(at 490.6137 -35.687)
		(property "Reference" "CR25W1"
			(at -1.495806 -1.067816 0)
			(unlocked yes)
			(layer "F.SilkS")
			(effects
				(font
					(size 0.4064 0.254)
					(thickness 0.1524)
				)
				(justify left)
			)
		)
		(property "Value" ""
			(at 0 0 0)
			(layer "F.Fab")
			(effects
				(font
					(size 1.27 1.27)
				)
			)
		)
		(duplicate_pad_numbers_are_jumpers no)
		(fp_circle
			(center -0.589026 -0.5334)
			(end -0.462026 -0.5334)
			(stroke
				(width 0.254)
				(type default)
			)
			(fill no)
			(layer "F.SilkS")
		)
		(fp_rect
			(start -0.225552 2.167382)
			(end 0.809498 -0.167386)
			(stroke
				(width 0)
				(type default)
			)
			(fill no)
			(layer "F.CrtYd")
		)
		(fp_line
			(start -0.225552 -0.167386)
			(end 0.809498 -0.167386)
			(stroke
				(width 0.1)
				(type default)
			)
			(layer "F.Fab")
		)
		(fp_line
			(start -0.225552 2.167382)
			(end -0.225552 -0.167386)
			(stroke
				(width 0.1)
				(type default)
			)
			(layer "F.Fab")
		)
		(fp_line
			(start 0.809498 -0.167386)
			(end 0.809498 2.167382)
			(stroke
				(width 0.1)
				(type default)
			)
			(layer "F.Fab")
		)
		(fp_line
			(start 0.809498 2.167382)
			(end -0.225552 2.167382)
			(stroke
				(width 0.1)
				(type default)
			)
			(layer "F.Fab")
		)
		(fp_circle
			(center -0.589026 -0.5334)
			(end -0.462026 -0.5334)
			(stroke
				(width 0.254)
				(type default)
			)
			(fill no)
			(layer "F.Fab")
		)
		(pad "1" smd rect
			(at 0 0)
			(size 0.3556 0.2032)
			(layers "F.Cu" "F.Mask" "F.Paste")
			(net "V_IO_B_J")
		)
		(pad "2" smd rect
			(at 0 0.500126)
			(size 0.3556 0.2032)
			(layers "F.Cu" "F.Mask" "F.Paste")
			(net "V_IO_G_J")
		)
		(pad "3" smd rect
			(at 0.2921 0.999998)
			(size 0.9398 0.4064)
			(layers "F.Cu" "F.Mask" "F.Paste")
			(net "GND")
		)
		(pad "4" smd rect
			(at 0 1.500124)
			(size 0.3556 0.2032)
			(layers "F.Cu" "F.Mask" "F.Paste")
			(net "V_IO_R_J")
		)
		(pad "5" smd rect
			(at 0 1.999996)
			(size 0.3556 0.2032)
			(layers "F.Cu" "F.Mask" "F.Paste")
			(net "Net_6484")
		)
		(pad "6" smd rect
			(at 0.583946 1.999996)
			(size 0.3556 0.2032)
			(layers "F.Cu" "F.Mask" "F.Paste")
			(net "Net_6483")
		)
		(pad "7" smd rect
			(at 0.583946 1.500124)
			(size 0.3556 0.2032)
			(layers "F.Cu" "F.Mask" "F.Paste")
			(net "V_IO_R_J")
		)
		(pad "8" smd rect
			(at 0.583946 0.500126)
			(size 0.3556 0.2032)
			(layers "F.Cu" "F.Mask" "F.Paste")
			(net "V_IO_G_J")
		)
		(pad "9" smd rect
			(at 0.583946 0)
			(size 0.3556 0.2032)
			(layers "F.Cu" "F.Mask" "F.Paste")
			(net "V_IO_B_J")
		)
	)
	(footprint ""
		(layer "F.Cu")
		(at 465.593938 -26.557224 90)
		(property "Reference" "R8E25"
			(at 0 0 90)
			(layer "F.SilkS")
			(hide yes)
			(effects
				(font
					(size 1.27 1.27)
				)
			)
		)
		(property "Value" ""
			(at 0 0 90)
			(layer "F.Fab")
			(effects
				(font
					(size 1.27 1.27)
				)
			)
		)
		(duplicate_pad_numbers_are_jumpers no)
		(fp_rect
			(start -0.2794 -0.1016)
			(end 0.2794 0.9906)
			(stroke
				(width 0)
				(type default)
			)
			(fill no)
			(layer "F.CrtYd")
		)
		(fp_line
			(start 0.2794 -0.1016)
			(end -0.2794 -0.1016)
			(stroke
				(width 0.1)
				(type default)
			)
			(layer "F.Fab")
		)
		(fp_line
			(start -0.2794 -0.1016)
			(end -0.2794 0.9906)
			(stroke
				(width 0.1)
				(type default)
			)
			(layer "F.Fab")
		)
		(fp_line
			(start 0.2794 0.9906)
			(end 0.2794 -0.1016)
			(stroke
				(width 0.1)
				(type default)
			)
			(layer "F.Fab")
		)
		(fp_line
			(start -0.2794 0.9906)
			(end 0.2794 0.9906)
			(stroke
				(width 0.1)
				(type default)
			)
			(layer "F.Fab")
		)
		(pad "1" smd rect
			(at 0 0 90)
			(size 0.508 0.508)
			(layers "F.Cu" "F.Mask" "F.Paste")
			(net "P3V3_STBY")
		)
		(pad "2" smd rect
			(at 0 0.889 90)
			(size 0.508 0.508)
			(layers "F.Cu" "F.Mask" "F.Paste")
			(net "VSENSE_P3V3_STBY")
		)
		(zone
			(layer "F.Cu")
			(hatch none 0.5)
			(connect_pads
				(clearance 0)
			)
			(min_thickness 0.25)
			(keepout
				(tracks not_allowed)
				(vias allowed)
				(pads allowed)
				(copperpour not_allowed)
				(footprints allowed)
			)
			(placement
				(enabled no)
				(sheetname "")
			)
			(fill
				(thermal_gap 0.5)
				(thermal_bridge_width 0.5)
				(island_removal_mode 0)
			)
			(polygon
				(pts
					(xy 465.847938 -26.303224) (xy 466.228938 -26.303224) (xy 466.228938 -26.811224) (xy 465.847938 -26.811224)
				)
			)
		)
		(zone
			(layer "F.Cu")
			(hatch none 0.5)
			(connect_pads
				(clearance 0)
			)
			(min_thickness 0.25)
			(keepout
				(tracks allowed)
				(vias not_allowed)
				(pads allowed)
				(copperpour not_allowed)
				(footprints allowed)
			)
			(placement
				(enabled no)
				(sheetname "")
			)
			(fill
				(thermal_gap 0.5)
				(thermal_bridge_width 0.5)
				(island_removal_mode 0)
			)
			(polygon
				(pts
					(xy 465.847938 -26.303224) (xy 466.228938 -26.303224) (xy 466.228938 -26.811224) (xy 465.847938 -26.811224)
				)
			)
		)
	)
	(footprint ""
		(layer "F.Cu")
		(at 354.36048 -135.742934)
		(property "Reference" "C7A37"
			(at 0 0 0)
			(layer "F.SilkS")
			(hide yes)
			(effects
				(font
					(size 1.27 1.27)
				)
			)
		)
		(property "Value" ""
			(at 0 0 0)
			(layer "F.Fab")
			(effects
				(font
					(size 1.27 1.27)
				)
			)
		)
		(duplicate_pad_numbers_are_jumpers no)
		(fp_poly
			(pts
				(xy 0.3048 -0.1016) (xy 0.3048 0.9906) (xy -0.3048 0.9906) (xy -0.3048 -0.1016)
			)
			(stroke
				(width 0)
				(type default)
			)
			(fill no)
			(layer "F.CrtYd")
		)
		(fp_line
			(start -0.3048 -0.1016)
			(end -0.3048 0.9906)
			(stroke
				(width 0.1)
				(type default)
			)
			(layer "F.Fab")
		)
		(fp_line
			(start -0.3048 0.9906)
			(end 0.3048 0.9906)
			(stroke
				(width 0.1)
				(type default)
			)
			(layer "F.Fab")
		)
		(fp_line
			(start 0.3048 -0.1016)
			(end -0.3048 -0.1016)
			(stroke
				(width 0.1)
				(type default)
			)
			(layer "F.Fab")
		)
		(fp_line
			(start 0.3048 0.9906)
			(end 0.3048 -0.1016)
			(stroke
				(width 0.1)
				(type default)
			)
			(layer "F.Fab")
		)
		(pad "1" smd rect
			(at 0 0)
			(size 0.508 0.508)
			(layers "F.Cu" "F.Mask" "F.Paste")
			(net "VR_PVDDQ_DEF_VDD")
		)
		(pad "2" smd rect
			(at 0 0.889)
			(size 0.508 0.508)
			(layers "F.Cu" "F.Mask" "F.Paste")
			(net "GND")
		)
		(zone
			(layer "F.Cu")
			(hatch none 0.5)
			(connect_pads
				(clearance 0)
			)
			(min_thickness 0.25)
			(keepout
				(tracks allowed)
				(vias not_allowed)
				(pads allowed)
				(copperpour not_allowed)
				(footprints allowed)
			)
			(placement
				(enabled no)
				(sheetname "")
			)
			(fill
				(thermal_gap 0.5)
				(thermal_bridge_width 0.5)
				(island_removal_mode 0)
			)
			(polygon
				(pts
					(xy 354.10648 -135.488934) (xy 354.61448 -135.488934) (xy 354.61448 -135.107934) (xy 354.10648 -135.107934)
				)
			)
		)
		(zone
			(layer "F.Cu")
			(hatch none 0.5)
			(connect_pads
				(clearance 0)
			)
			(min_thickness 0.25)
			(keepout
				(tracks not_allowed)
				(vias allowed)
				(pads allowed)
				(copperpour not_allowed)
				(footprints allowed)
			)
			(placement
				(enabled no)
				(sheetname "")
			)
			(fill
				(thermal_gap 0.5)
				(thermal_bridge_width 0.5)
				(island_removal_mode 0)
			)
			(polygon
				(pts
					(xy 354.10648 -135.107934) (xy 354.61448 -135.107934) (xy 354.61448 -135.488934) (xy 354.10648 -135.488934)
				)
			)
		)
	)
	(footprint ""
		(layer "F.Cu")
		(at 28.794964 -88.540844 -90)
		(property "Reference" "R1D52"
			(at 0 0 270)
			(layer "F.SilkS")
			(hide yes)
			(effects
				(font
					(size 1.27 1.27)
				)
			)
		)
		(property "Value" ""
			(at 0 0 270)
			(layer "F.Fab")
			(effects
				(font
					(size 1.27 1.27)
				)
			)
		)
		(duplicate_pad_numbers_are_jumpers no)
		(fp_poly
			(pts
				(xy -0.2794 -0.1016) (xy 0.2794 -0.1016) (xy 0.2794 0.9906) (xy -0.2794 0.9906)
			)
			(stroke
				(width 0)
				(type default)
			)
			(fill no)
			(layer "F.CrtYd")
		)
		(fp_line
			(start -0.2794 0.9906)
			(end 0.2794 0.9906)
			(stroke
				(width 0.1)
				(type default)
			)
			(layer "F.Fab")
		)
		(fp_line
			(start 0.2794 0.9906)
			(end 0.2794 -0.1016)
			(stroke
				(width 0.1)
				(type default)
			)
			(layer "F.Fab")
		)
		(fp_line
			(start -0.2794 -0.1016)
			(end -0.2794 0.9906)
			(stroke
				(width 0.1)
				(type default)
			)
			(layer "F.Fab")
		)
		(fp_line
			(start 0.2794 -0.1016)
			(end -0.2794 -0.1016)
			(stroke
				(width 0.1)
				(type default)
			)
			(layer "F.Fab")
		)
		(pad "1" smd rect
			(at 0 0 270)
			(size 0.508 0.508)
			(layers "F.Cu" "F.Mask" "F.Paste")
			(net "VR_PVCCIN_CPU1_PH5_OCSET")
		)
		(pad "2" smd rect
			(at 0 0.889 270)
			(size 0.508 0.508)
			(layers "F.Cu" "F.Mask" "F.Paste")
			(net "GND")
		)
		(zone
			(layer "F.Cu")
			(hatch none 0.5)
			(connect_pads
				(clearance 0)
			)
			(min_thickness 0.25)
			(keepout
				(tracks not_allowed)
				(vias allowed)
				(pads allowed)
				(copperpour not_allowed)
				(footprints allowed)
			)
			(placement
				(enabled no)
				(sheetname "")
			)
			(fill
				(thermal_gap 0.5)
				(thermal_bridge_width 0.5)
				(island_removal_mode 0)
			)
			(polygon
				(pts
					(xy 28.159964 -88.794844) (xy 28.159964 -88.286844) (xy 28.540964 -88.286844) (xy 28.540964 -88.794844)
				)
			)
		)
		(zone
			(layer "F.Cu")
			(hatch none 0.5)
			(connect_pads
				(clearance 0)
			)
			(min_thickness 0.25)
			(keepout
				(tracks allowed)
				(vias not_allowed)
				(pads allowed)
				(copperpour not_allowed)
				(footprints allowed)
			)
			(placement
				(enabled no)
				(sheetname "")
			)
			(fill
				(thermal_gap 0.5)
				(thermal_bridge_width 0.5)
				(island_removal_mode 0)
			)
			(polygon
				(pts
					(xy 28.540964 -88.794844) (xy 28.540964 -88.286844) (xy 28.159964 -88.286844) (xy 28.159964 -88.794844)
				)
			)
		)
	)
)
